FILE_TYPE = MULTI_PHYS_TABLE;

PART 'NCT7718W'

{========================================================================================}
:VALUE      | PART_TYPE | MATERIAL | PART_NUMBER    = STANDARD | LIFECYCLE      | PART_NUMBER   | JEDEC_TYPE         | DESCRIPTION                   | MANUFTR | MANUF_PN   | RD_CMPLS_LVL | CMPLS_LVL | FROM_PJ    | CLASS | DIP_SMD | DATA               | EE_CHECK_LIST | FP_ECN         | PSL | CREATOR | STATUS | MSD | ESD_CDM | ESD_HBM | ESD_MM | PIN_LENGTH_SHORT_PIN | PIN_LENGTH_LONG_PIN | CREATEDAY  ;
{========================================================================================}
 'NCT7718W' | 'SMLF'    | 'IC'     | 'AL007718001'(!) = ''       | ''               | 'AL007718001' |'MSOP8_0-65_3X3XE'| 'IC OTHER(8P) NCT7718W(MSOP)' | 'NVT'   | 'NCT7718W' | 'EP(V1)'     | 'EP(V1)'  | 'F0EG-RAY' | 'IC'  | ''      | 'NVT_NCT7718W.pdf' | ''            | 'NCT7718W.msg' | ''  | ''      | ''     | ''  | ''      | ''      | ''     | '0 MILS'             | '0 MILS'            | '20220317'
 'NCT7718W' | 'SMLF'    | 'EMPTY'  | 'AL007718001'(!) = ''       | ''               | 'AL007718001' |'MSOP8_0-65_3X3XE'| 'IC OTHER(8P) NCT7718W(MSOP)' | 'NVT'   | 'NCT7718W' | 'EP(V1)'     | 'EP(V1)'  | 'F0EG-RAY' | 'IC'  | ''      | 'NVT_NCT7718W.pdf' | ''            | 'NCT7718W.msg' | ''  | ''      | ''     | ''  | ''      | ''      | ''     | '0 MILS'             | '0 MILS'            | '20220317'

END_PART

END.

